# S9S_MB_2U (Grand Teton) — schematic netlist excerpt (pin names and nets, part order shuffled) for the footprints in the layout excerpt that follows; sources: Cadence DE-HDL packaged netlist, KiCad conversion of 03242023_DA0F0TMBIJ0_F0T_Motherboard_J_brd_V01_OCP.brd

C900  Q_CAP_DIFFBUS  DIFF BUS_0.22UF 6.3V 20% X6S  pkg C0201  page 174 : \1\ = P5E_CPU0_PE3_TX_C_DN<0> ; \2\ = P5E_CPU0_PE3_TX_DN<0>
C1290  Q_CAP  1UF 25V 10% X6S  pkg C0402  page 239 : A = P3V3_AUX ; B = GND
R4420  Q_RES  49.9 1% EMPTY  pkg 0402LF  page 152 : A = USB2_HOST_BMC_B_DN ; B = GND

(kicad_pcb
	(version 20260206)
	(generator "pcbnew")
	(generator_version "10.0")
	(general
		(thickness 1.6)
		(legacy_teardrops no)
	)
	(paper "A4")
	(title_block
		(title "03242023_DA0F0TMBIJ0_F0T_Motherboard_J_brd_V01_OCP.brd")
		(comment 1 "Grand Teton / footprints 726-728 of 6105")
	)
	(layers
		(0 "F.Cu" signal "TOP")
		(4 "In1.Cu" signal "GND")
		(6 "In2.Cu" signal "IN1")
		(8 "In3.Cu" signal "GND1")
		(10 "In4.Cu" signal "IN2")
		(12 "In5.Cu" signal "GND2")
		(14 "In6.Cu" signal "IN3")
		(16 "In7.Cu" signal "GND3")
		(18 "In8.Cu" signal "VCC")
		(20 "In9.Cu" signal "VCC1")
		(22 "In10.Cu" signal "GND4")
		(24 "In11.Cu" signal "IN4")
		(26 "In12.Cu" signal "GND5")
		(28 "In13.Cu" signal "IN5")
		(30 "In14.Cu" signal "GND6")
		(32 "In15.Cu" signal "IN6")
		(34 "In16.Cu" signal "GND7")
		(2 "B.Cu" signal "BOTTOM")
		(9 "F.Adhes" user "F.Adhesive")
		(11 "B.Adhes" user "B.Adhesive")
		(13 "F.Paste" user "Package Geometry/Pastemask Top")
		(15 "B.Paste" user "Package Geometry/Pastemask Bottom")
		(5 "F.SilkS" user "Ref Des/Silkscreen Top")
		(7 "B.SilkS" user "Ref Des/Silkscreen Bottom")
		(1 "F.Mask" user "Board Geometry/Soldermask Top")
		(3 "B.Mask" user "Board Geometry/Soldermask Bottom")
		(17 "Dwgs.User" user "User.Drawings")
		(19 "Cmts.User" user "User.Comments")
		(21 "Eco1.User" user "User.Eco1")
		(23 "Eco2.User" user "User.Eco2")
		(25 "Edge.Cuts" user "Board Geometry/Outline")
		(27 "Margin" user)
		(31 "F.CrtYd" user "Package Geometry/Place Bound Top")
		(29 "B.CrtYd" user "Package Geometry/Place Bound Bottom")
		(35 "F.Fab" user "Ref Des/Assembly Top")
		(33 "B.Fab" user "Ref Des/Assembly Bottom")
	)
	(footprint ""
		(layer "F.Cu")
		(at 381.229616 -97.604072 -90)
		(property "Reference" "C1290"
			(at 0 0 270)
			(layer "F.SilkS")
			(hide yes)
			(effects
				(font
					(size 1.27 1.27)
				)
			)
		)
		(property "Value" ""
			(at 0 0 270)
			(layer "F.Fab")
			(effects
				(font
					(size 1.27 1.27)
				)
			)
		)
		(duplicate_pad_numbers_are_jumpers no)
		(fp_line
			(start -0.7874 0.4064)
			(end -0.7874 -0.4064)
			(stroke
				(width 0.1524)
				(type default)
			)
			(layer "F.SilkS")
		)
		(fp_line
			(start 0.7874 0.4064)
			(end -0.7874 0.4064)
			(stroke
				(width 0.1524)
				(type default)
			)
			(layer "F.SilkS")
		)
		(fp_line
			(start -0.7874 -0.4064)
			(end 0.7874 -0.4064)
			(stroke
				(width 0.1524)
				(type default)
			)
			(layer "F.SilkS")
		)
		(fp_line
			(start 0.7874 -0.4064)
			(end 0.7874 0.4064)
			(stroke
				(width 0.1524)
				(type default)
			)
			(layer "F.SilkS")
		)
		(fp_line
			(start -0.67945 0.3048)
			(end -0.67945 -0.305054)
			(stroke
				(width 0.1)
				(type default)
			)
			(layer "F.Fab")
		)
		(fp_line
			(start -0.12065 0.3048)
			(end -0.67945 0.3048)
			(stroke
				(width 0.1)
				(type default)
			)
			(layer "F.Fab")
		)
		(fp_line
			(start 0.120396 0.3048)
			(end 0.120396 0.2794)
			(stroke
				(width 0.1)
				(type default)
			)
			(layer "F.Fab")
		)
		(fp_line
			(start 0.67945 0.3048)
			(end 0.120396 0.3048)
			(stroke
				(width 0.1)
				(type default)
			)
			(layer "F.Fab")
		)
		(fp_line
			(start -0.12065 0.2794)
			(end -0.12065 0.3048)
			(stroke
				(width 0.1)
				(type default)
			)
			(layer "F.Fab")
		)
		(fp_line
			(start 0.120396 0.2794)
			(end -0.12065 0.2794)
			(stroke
				(width 0.1)
				(type default)
			)
			(layer "F.Fab")
		)
		(fp_line
			(start -0.12065 -0.2794)
			(end 0.12065 -0.2794)
			(stroke
				(width 0.1)
				(type default)
			)
			(layer "F.Fab")
		)
		(fp_line
			(start 0.12065 -0.2794)
			(end 0.12065 -0.3048)
			(stroke
				(width 0.1)
				(type default)
			)
			(layer "F.Fab")
		)
		(fp_line
			(start 0.12065 -0.3048)
			(end 0.67945 -0.3048)
			(stroke
				(width 0.1)
				(type default)
			)
			(layer "F.Fab")
		)
		(fp_line
			(start 0.67945 -0.3048)
			(end 0.67945 0.3048)
			(stroke
				(width 0.1)
				(type default)
			)
			(layer "F.Fab")
		)
		(fp_line
			(start -0.67945 -0.305054)
			(end -0.12065 -0.305054)
			(stroke
				(width 0.1)
				(type default)
			)
			(layer "F.Fab")
		)
		(fp_line
			(start -0.12065 -0.305054)
			(end -0.12065 -0.2794)
			(stroke
				(width 0.1)
				(type default)
			)
			(layer "F.Fab")
		)
		(pad "1" smd circle
			(at -0.40005 0 270)
			(size 0 0)
			(layers "F.Cu" "F.Mask" "F.Paste")
			(net "P3V3_AUX")
		)
		(pad "2" smd circle
			(at 0.40005 0 270)
			(size 0 0)
			(layers "F.Cu" "F.Mask" "F.Paste")
			(net "GND")
		)
	)
	(footprint ""
		(layer "F.Cu")
		(at 419.60673 -408.517344 -90)
		(property "Reference" "C900"
			(at 0 0 270)
			(layer "F.SilkS")
			(hide yes)
			(effects
				(font
					(size 1.27 1.27)
				)
			)
		)
		(property "Value" ""
			(at 0 0 270)
			(layer "F.Fab")
			(effects
				(font
					(size 1.27 1.27)
				)
			)
		)
		(duplicate_pad_numbers_are_jumpers no)
		(fp_line
			(start -0.299974 0.150114)
			(end -0.299974 -0.150114)
			(stroke
				(width 0.1)
				(type default)
			)
			(layer "F.Fab")
		)
		(fp_line
			(start 0.299974 0.150114)
			(end -0.299974 0.150114)
			(stroke
				(width 0.1)
				(type default)
			)
			(layer "F.Fab")
		)
		(fp_line
			(start -0.299974 -0.150114)
			(end 0.299974 -0.150114)
			(stroke
				(width 0.1)
				(type default)
			)
			(layer "F.Fab")
		)
		(fp_line
			(start 0.299974 -0.150114)
			(end 0.299974 0.150114)
			(stroke
				(width 0.1)
				(type default)
			)
			(layer "F.Fab")
		)
		(pad "1" smd rect
			(at -0.2667 0 270)
			(size 0.3048 0.381)
			(layers "F.Cu" "F.Mask" "F.Paste")
			(net "P5E_CPU0_PE3_TX_C_DN<0>")
		)
		(pad "2" smd rect
			(at 0.2667 0 270)
			(size 0.3048 0.381)
			(layers "F.Cu" "F.Mask" "F.Paste")
			(net "P5E_CPU0_PE3_TX_DN<0>")
		)
	)
	(footprint ""
		(layer "F.Cu")
		(at 17.658842 -105.537762 90)
		(property "Reference" "R4420"
			(at 0 0 90)
			(layer "F.SilkS")
			(hide yes)
			(effects
				(font
					(size 1.27 1.27)
				)
			)
		)
		(property "Value" ""
			(at 0 0 90)
			(layer "F.Fab")
			(effects
				(font
					(size 1.27 1.27)
				)
			)
		)
		(duplicate_pad_numbers_are_jumpers no)
		(fp_line
			(start 0.7874 -0.4064)
			(end 0.7874 0.4064)
			(stroke
				(width 0.1524)
				(type default)
			)
			(layer "F.SilkS")
		)
		(fp_line
			(start -0.026162 -0.4064)
			(end 0.7874 -0.4064)
			(stroke
				(width 0.1524)
				(type default)
			)
			(layer "F.SilkS")
		)
		(fp_line
			(start 0.7874 0.4064)
			(end -0.7874 0.4064)
			(stroke
				(width 0.1524)
				(type default)
			)
			(layer "F.SilkS")
		)
		(fp_line
			(start -0.7874 0.4064)
			(end -0.7874 -0.4064)
			(stroke
				(width 0.1524)
				(type default)
			)
			(layer "F.SilkS")
		)
		(fp_line
			(start -0.12065 -0.305054)
			(end -0.12065 -0.2794)
			(stroke
				(width 0.1)
				(type default)
			)
			(layer "F.Fab")
		)
		(fp_line
			(start -0.67945 -0.305054)
			(end -0.12065 -0.305054)
			(stroke
				(width 0.1)
				(type default)
			)
			(layer "F.Fab")
		)
		(fp_line
			(start 0.67945 -0.3048)
			(end 0.67945 0.3048)
			(stroke
				(width 0.1)
				(type default)
			)
			(layer "F.Fab")
		)
		(fp_line
			(start 0.12065 -0.3048)
			(end 0.67945 -0.3048)
			(stroke
				(width 0.1)
				(type default)
			)
			(layer "F.Fab")
		)
		(fp_line
			(start 0.12065 -0.2794)
			(end 0.12065 -0.3048)
			(stroke
				(width 0.1)
				(type default)
			)
			(layer "F.Fab")
		)
		(fp_line
			(start -0.12065 -0.2794)
			(end 0.12065 -0.2794)
			(stroke
				(width 0.1)
				(type default)
			)
			(layer "F.Fab")
		)
		(fp_line
			(start 0.120396 0.2794)
			(end -0.12065 0.2794)
			(stroke
				(width 0.1)
				(type default)
			)
			(layer "F.Fab")
		)
		(fp_line
			(start -0.12065 0.2794)
			(end -0.12065 0.3048)
			(stroke
				(width 0.1)
				(type default)
			)
			(layer "F.Fab")
		)
		(fp_line
			(start 0.67945 0.3048)
			(end 0.120396 0.3048)
			(stroke
				(width 0.1)
				(type default)
			)
			(layer "F.Fab")
		)
		(fp_line
			(start 0.120396 0.3048)
			(end 0.120396 0.2794)
			(stroke
				(width 0.1)
				(type default)
			)
			(layer "F.Fab")
		)
		(fp_line
			(start -0.12065 0.3048)
			(end -0.67945 0.3048)
			(stroke
				(width 0.1)
				(type default)
			)
			(layer "F.Fab")
		)
		(fp_line
			(start -0.67945 0.3048)
			(end -0.67945 -0.305054)
			(stroke
				(width 0.1)
				(type default)
			)
			(layer "F.Fab")
		)
		(pad "1" smd circle
			(at -0.40005 0 90)
			(size 0 0)
			(layers "F.Cu" "F.Mask" "F.Paste")
			(net "USB2_HOST_BMC_B_DN")
		)
		(pad "2" smd circle
			(at 0.40005 0 90)
			(size 0 0)
			(layers "F.Cu" "F.Mask" "F.Paste")
			(net "GND")
		)
	)
)
